%FSTAX23Y23*%
%MOIN*%
%SFA1B1*%

%IPPOS*%
%ADD9500C,0.008000*%
%ADD9501C,0.016000*%
%ADD9502C,0.021660*%
%ADD9503C,0.029920*%
%ADD9504C,0.030000*%
%ADD9505C,0.041340*%
%ADD9506C,0.050000*%
%ADD9507C,0.060000*%
%ADD9508C,0.064960*%
%ADD9509C,0.068000*%
%ADD9510C,0.070870*%
%ADD9511C,0.118110*%
%ADD9512C,0.125980*%
%ADD9513C,0.035430*%
%ADD9514C,0.065980*%
%ADD9515C,0.118110*%
%ADD9516C,0.125200*%
%LNtimingcard_pcb-roundholes-1*%
%LPD*%
G54D9500*
X03602Y00641D03*
X03603Y00682D03*
X02893Y00795D03*
X02862D03*
X02826D03*
X02799D03*
X02759D03*
X02732D03*
X02692D03*
X02665D03*
X02625D03*
X02598D03*
X02606Y00931D03*
X02622Y00976D03*
X02649D03*
X02681D03*
X02708D03*
X0274D03*
X02767D03*
X02799D03*
X02826D03*
X02905Y00937D03*
X02901Y01106D03*
X0285D03*
X02787D03*
X02728D03*
X02665D03*
X0261D03*
X02511Y01105D03*
X02409Y01106D03*
X02311D03*
X02314Y00933D03*
X02413D03*
X02478Y00937D03*
X02515Y00933D03*
X02511Y00405D03*
X02469Y0041D03*
X02389Y00405D03*
X0235D03*
X02413Y00279D03*
X02444D03*
X02447Y00242D03*
X02546Y00244D03*
X02578Y00279D03*
X0261D03*
X02636Y00247D03*
X02748Y00282D03*
X02779Y00279D03*
X02799Y00251D03*
X02878Y00249D03*
X02905Y00279D03*
X02937Y00279D03*
X02957Y00251D03*
X03097D03*
X03019Y00405D03*
X0298Y00409D03*
X02854Y00405D03*
X02821Y00407D03*
X02704Y00405D03*
X02665D03*
X02309Y00246D03*
X02151Y00255D03*
Y00287D03*
X02112D03*
Y00255D03*
X02076D03*
Y00287D03*
X02034Y00246D03*
X01916Y00244D03*
X01872Y00255D03*
X01852D03*
X01832D03*
Y00287D03*
X01852D03*
X01872D03*
X01797Y00355D03*
X01256Y00942D03*
X01004Y00906D03*
X0099Y00687D03*
X00654Y0079D03*
X00655Y01028D03*
X01003Y01177D03*
X01008Y0143D03*
X01242Y01472D03*
X01671Y01497D03*
X01718D03*
X01719Y01536D03*
X01714Y01595D03*
X0167D03*
Y01685D03*
X01721D03*
X01718Y01792D03*
X01671D03*
X01675Y01891D03*
X01721Y0189D03*
Y01989D03*
X01674D03*
X01568Y02067D03*
X01619Y02121D03*
X01754Y02126D03*
X01248Y02D03*
X01009Y01956D03*
X01015Y01705D03*
X01393Y01816D03*
X01671Y01399D03*
X01716D03*
X01798Y01304D03*
X01567Y01285D03*
X00654Y01314D03*
X00653Y01551D03*
X00654Y01839D03*
Y02073D03*
Y02365D03*
X00653Y02593D03*
X0102Y02481D03*
X01261Y02482D03*
X00937Y02317D03*
X00996Y02256D03*
X01884Y02071D03*
X01879Y01811D03*
X01893Y01685D03*
X01822Y01674D03*
X01897Y01516D03*
X02028Y01361D03*
X02004Y01336D03*
X02059Y01386D03*
X02083Y01411D03*
X02206Y01298D03*
X02274Y01506D03*
X02446Y01437D03*
X02502Y01316D03*
X02694Y01481D03*
X02719Y01591D03*
X02643Y01616D03*
X02666Y0164D03*
X02604Y01734D03*
X02626Y0177D03*
X02579Y0179D03*
X02549Y01755D03*
X02384Y01941D03*
X02409Y01967D03*
X02299Y01916D03*
X0233Y02215D03*
X02409Y02283D03*
Y02314D03*
X0245Y02282D03*
X02475Y02291D03*
X02499Y02236D03*
X02579Y02281D03*
X02618Y02299D03*
X02645Y0227D03*
X02671Y02291D03*
X02702Y02289D03*
X02726Y02293D03*
X02685Y02311D03*
X02803Y02307D03*
X02841Y02263D03*
X02874Y0229D03*
X02942Y02286D03*
X02985Y02287D03*
X0292Y02428D03*
X02894Y02431D03*
X02948Y02456D03*
X02958Y02621D03*
X02881Y02566D03*
X02821Y02601D03*
X02779D03*
X02688D03*
X0259D03*
X02488Y02574D03*
X02494Y02661D03*
Y02696D03*
X02394Y0272D03*
X02419Y02788D03*
X02429Y02621D03*
X02385Y02613D03*
X02279Y02614D03*
X02252Y02613D03*
X02272Y02463D03*
X02322Y02429D03*
X02421D03*
X02484D03*
X02525Y02463D03*
X02575Y02412D03*
X02599Y02436D03*
X02624Y02461D03*
X02783Y02433D03*
X02692Y02721D03*
X03051Y02732D03*
X03342Y02263D03*
X03298Y01971D03*
X03329Y01826D03*
X03252Y01661D03*
X03224Y01661D03*
X03197Y01714D03*
X03056Y01811D03*
X02894Y01561D03*
X02919Y01536D03*
X03379Y01386D03*
Y01336D03*
X02146Y02753D03*
X03414Y02736D03*
X03623Y02587D03*
X03498Y02341D03*
X03571Y02058D03*
Y02033D03*
X03554Y01991D03*
Y01941D03*
Y01891D03*
Y01841D03*
X03439Y0187D03*
X03392Y01871D03*
X03414Y01805D03*
X0341Y01713D03*
X03413Y01573D03*
X03406Y01461D03*
X03407Y01411D03*
X03404Y01363D03*
X03549Y01413D03*
Y01441D03*
X03594Y01514D03*
X0359Y01662D03*
X03589Y01711D03*
X03718Y01713D03*
X03712Y01673D03*
X03747Y01679D03*
X03773Y01666D03*
X03803Y01691D03*
X03804Y0184D03*
X03719Y01766D03*
Y01921D03*
Y01996D03*
X03944Y01816D03*
X04064Y01796D03*
X04134Y01751D03*
X04131Y01686D03*
X04134Y01651D03*
X04151Y01623D03*
X04179Y01601D03*
X04034Y01546D03*
X03994Y01551D03*
X03969Y01552D03*
X03924Y01536D03*
X03894Y01566D03*
X03864Y01511D03*
X03834Y01481D03*
X03732Y01418D03*
X04064Y01511D03*
X03968Y01671D03*
X03996Y01711D03*
X04039Y02406D03*
X04064Y02722D03*
X0396Y02724D03*
X04234Y02725D03*
X04339D03*
X04503Y02789D03*
X04794Y02808D03*
X05577Y02214D03*
X05634Y02236D03*
X06048Y02171D03*
X06003Y0243D03*
X06274Y02391D03*
X0645Y02462D03*
Y02535D03*
X06452Y02606D03*
X06451Y02673D03*
X0645Y0274D03*
X06424Y02181D03*
X06395Y02111D03*
X06607Y02176D03*
X06699Y01881D03*
X06694Y0183D03*
X06594Y01775D03*
Y0172D03*
Y01673D03*
Y0161D03*
X06587Y01529D03*
X06628Y01372D03*
X06978Y0183D03*
X06949Y02095D03*
X06649Y03003D03*
X06647Y03129D03*
X06648Y03341D03*
X06509Y03456D03*
X06479Y03426D03*
X06447Y03396D03*
X06409Y03371D03*
X06354Y03331D03*
X06334Y03266D03*
X06262Y0322D03*
X06287Y03195D03*
X06304Y03121D03*
X06335Y03147D03*
X06439Y03191D03*
X06476Y03231D03*
X06444Y03291D03*
X06456Y03009D03*
X06362Y02952D03*
X06274Y02949D03*
X06294Y03701D03*
X05733Y03556D03*
X05676Y03546D03*
X05274Y03511D03*
X0522Y04086D03*
X0491Y04203D03*
X04754Y04115D03*
X04387Y04206D03*
X04393Y03976D03*
X04194Y03884D03*
X04085Y03892D03*
X04039Y03784D03*
X04053Y03641D03*
X04116Y03597D03*
X04318Y03507D03*
X04385Y03661D03*
X04437D03*
X04523Y03736D03*
X04254Y03776D03*
X0383Y03762D03*
X03829Y03806D03*
X03699Y03836D03*
Y03751D03*
X03539Y03806D03*
X03531Y0366D03*
X03424Y03636D03*
X03437Y03476D03*
X03469Y03456D03*
X03394Y03447D03*
X03491Y03297D03*
X03542Y03318D03*
X03657Y03296D03*
X03744Y03261D03*
Y03342D03*
X03806Y03235D03*
X03799Y03201D03*
X03829Y03176D03*
X03854Y03151D03*
X03877Y03078D03*
X03939Y03121D03*
X04068Y03135D03*
X04114D03*
X04152D03*
X04208D03*
X04272D03*
X04333D03*
X04431D03*
X04477D03*
X04438Y03354D03*
X03622Y03486D03*
X03717Y03072D03*
X03491Y03103D03*
X03414Y02892D03*
X03504Y04086D03*
X03395Y04222D03*
X03777Y04023D03*
X03269Y03788D03*
X03219Y03806D03*
X03239Y03596D03*
X03358Y03448D03*
X03302Y03344D03*
X0333Y03301D03*
X03263Y03303D03*
X0323Y03235D03*
X03188Y03187D03*
X03183Y03135D03*
X03275Y03141D03*
X03277Y02963D03*
X03197Y0297D03*
X03344Y02996D03*
X03368Y0305D03*
X03374Y03273D03*
X0307Y03393D03*
X02993Y03751D03*
X03014Y03831D03*
X0286Y03787D03*
X02722Y03786D03*
X02724Y03729D03*
X02679Y03661D03*
X02674Y03501D03*
X0272Y03494D03*
X02774Y03566D03*
X02799Y03616D03*
X02579Y03486D03*
X02634Y03406D03*
X0259Y03288D03*
X02591Y03186D03*
X02462Y03172D03*
X02414Y03199D03*
X02418Y03118D03*
X02413Y03295D03*
X02321Y03361D03*
X02259Y03261D03*
X02205Y032D03*
X02254Y03536D03*
X02389Y03481D03*
X02434Y03546D03*
X02139Y03611D03*
X02258Y03741D03*
X02029Y03836D03*
X02004Y03816D03*
X02059Y03871D03*
X02084Y03896D03*
X02146Y04103D03*
X02253Y04086D03*
X0229Y04217D03*
X02353Y04017D03*
X01903Y04018D03*
X01849Y03701D03*
X01884Y03601D03*
X02473Y0298D03*
X02633Y02921D03*
X0257Y04283D03*
X02888Y04221D03*
X01779Y04156D03*
X01749Y0411D03*
X01691Y04079D03*
X01569Y04171D03*
X01557Y04229D03*
X01345Y04175D03*
X01294Y04256D03*
X01408Y0398D03*
X0144Y03557D03*
X01549Y03621D03*
X01574Y03596D03*
X01754Y03661D03*
X01726Y04329D03*
X01788D03*
X01459Y03147D03*
G54D9501*
X06196Y02484D03*
X06838Y01649D03*
X05964Y03555D03*
G54D9502*
X02202Y00957D03*
X0299D03*
X01696Y01308D03*
Y02096D03*
X02202Y02437D03*
X0299D03*
X03571Y02096D03*
Y01308D03*
G54D9503*
X02422Y03082D03*
Y03239D03*
Y03443D03*
Y03601D03*
G54D9504*
X02043Y04057D03*
Y04157D03*
Y04257D03*
X01457Y04253D03*
Y04153D03*
Y04053D03*
G54D9505*
X05127Y01007D03*
X05327D03*
X04927D03*
X04327D03*
Y02307D03*
X04727D03*
X04927D03*
X05127D03*
X05327D03*
G54D9506*
X05578Y0089D03*
X03979D03*
Y02489D03*
X04062Y02595D03*
X0418D03*
X04298D03*
X05578Y02489D03*
Y01689D03*
G54D9507*
X00199Y00906D03*
Y01431D03*
Y01956D03*
Y02481D03*
G54D9508*
X05723Y03844D03*
Y04025D03*
G54D9509*
X00299Y00806D03*
Y01006D03*
X00099D03*
Y00806D03*
Y01331D03*
Y01531D03*
Y01856D03*
Y02056D03*
Y02381D03*
Y02581D03*
X00299D03*
Y02381D03*
Y02056D03*
Y01856D03*
Y01531D03*
Y01331D03*
G54D9510*
X06569Y03589D03*
X06734D03*
X069D03*
Y03806D03*
X06734D03*
X06569D03*
G54D9511*
X03617Y00915D03*
X01652D03*
X01651Y02485D03*
X03617D03*
G54D9512*
X02531Y0283D03*
Y03853D03*
X00149D03*
Y0283D03*
G54D9513*
X03784Y04126D03*
X03958D03*
G54D9514*
X02994Y04086D03*
X03294D03*
G54D9515*
X06569Y04093D03*
X069D03*
G54D9516*
X00285Y00368D03*
Y04152D03*
M02*